(kicad_pcb
	(version 20260206)
	(generator "pcbnew")
	(generator_version "10.0")
	(general
		(thickness 1.6)
		(legacy_teardrops no)
	)
	(paper "A4")
	(title_block
		(title "v1-chassis-manager — T6M_CM_d_v01_1031_1645.brd")
		(comment 1 "Open CloudServer (Microsoft) / footprint 110 of 2512 (U15), pads 1-96 of 96")
	)
	(layers
		(0 "F.Cu" signal "TOP")
		(4 "In1.Cu" signal "GND1")
		(6 "In2.Cu" signal "IN1")
		(8 "In3.Cu" signal "VCC1")
		(10 "In4.Cu" signal "VCC2")
		(12 "In5.Cu" signal "GND2")
		(14 "In6.Cu" signal "IN2")
		(16 "In7.Cu" signal "IN3")
		(18 "In8.Cu" signal "GND3")
		(2 "B.Cu" signal "BOTTOM")
		(9 "F.Adhes" user "F.Adhesive")
		(11 "B.Adhes" user "B.Adhesive")
		(13 "F.Paste" user "Package Geometry/Pastemask Top")
		(15 "B.Paste" user "Package Geometry/Pastemask Bottom")
		(5 "F.SilkS" user "Ref Des/Silkscreen Top")
		(7 "B.SilkS" user "Ref Des/Silkscreen Bottom")
		(1 "F.Mask" user "Board Geometry/Soldermask Top")
		(3 "B.Mask" user "Board Geometry/Soldermask Bottom")
		(17 "Dwgs.User" user "User.Drawings")
		(19 "Cmts.User" user "User.Comments")
		(21 "Eco1.User" user "User.Eco1")
		(23 "Eco2.User" user "User.Eco2")
		(25 "Edge.Cuts" user "Board Geometry/Outline")
		(27 "Margin" user)
		(31 "F.CrtYd" user "Package Geometry/Place Bound Top")
		(29 "B.CrtYd" user "Package Geometry/Place Bound Bottom")
		(35 "F.Fab" user "Ref Des/Assembly Top")
		(33 "B.Fab" user "Ref Des/Assembly Bottom")
	)
	(footprint ""
		(layer "F.Cu")
		(at 43.233086 -134.963662)
		(property "Reference" "U15"
			(at -7.777734 -0.440436 90)
			(unlocked yes)
			(layer "F.SilkS")
			(effects
				(font
					(size 0.7874 0.5842)
					(thickness 0.1524)
				)
				(justify left)
			)
		)
		(property "Value" ""
			(at 0 0 0)
			(layer "F.Fab")
			(effects
				(font
					(size 1.27 1.27)
				)
			)
		)
		(duplicate_pad_numbers_are_jumpers no)
		(pad "A1" smd circle
			(at -3.199892 -5.999988)
			(size 0.3683 0.3683)
			(layers "F.Cu" "F.Mask" "F.Paste")
			(net "P1V538_BMC_NODE1")
		)
		(pad "A2" smd circle
			(at -2.400046 -5.999988)
			(size 0.3683 0.3683)
			(layers "F.Cu" "F.Mask" "F.Paste")
			(net "BMC_NODE1_DDR_D15")
		)
		(pad "A3" smd circle
			(at -1.599946 -5.999988)
			(size 0.3683 0.3683)
			(layers "F.Cu" "F.Mask" "F.Paste")
			(net "BMC_NODE1_DDR_D14")
		)
		(pad "A7" smd circle
			(at 1.599946 -5.999988)
			(size 0.3683 0.3683)
			(layers "F.Cu" "F.Mask" "F.Paste")
			(net "BMC_NODE1_DDR_D10")
		)
		(pad "A8" smd circle
			(at 2.400046 -5.999988)
			(size 0.3683 0.3683)
			(layers "F.Cu" "F.Mask" "F.Paste")
			(net "P1V538_BMC_NODE1")
		)
		(pad "A9" smd circle
			(at 3.199892 -5.999988)
			(size 0.3683 0.3683)
			(layers "F.Cu" "F.Mask" "F.Paste")
			(net "GND")
		)
		(pad "B1" smd circle
			(at -3.199892 -5.199888)
			(size 0.3683 0.3683)
			(layers "F.Cu" "F.Mask" "F.Paste")
			(net "GND")
		)
		(pad "B2" smd circle
			(at -2.400046 -5.199888)
			(size 0.3683 0.3683)
			(layers "F.Cu" "F.Mask" "F.Paste")
			(net "P1V538_BMC_NODE1")
		)
		(pad "B3" smd circle
			(at -1.599946 -5.199888)
			(size 0.3683 0.3683)
			(layers "F.Cu" "F.Mask" "F.Paste")
			(net "GND")
		)
		(pad "B7" smd circle
			(at 1.599946 -5.199888)
			(size 0.3683 0.3683)
			(layers "F.Cu" "F.Mask" "F.Paste")
			(net "BMC_NODE1_DDR_DQS1_DN")
		)
		(pad "B8" smd circle
			(at 2.400046 -5.199888)
			(size 0.3683 0.3683)
			(layers "F.Cu" "F.Mask" "F.Paste")
			(net "BMC_NODE1_DDR_D9")
		)
		(pad "B9" smd circle
			(at 3.199892 -5.199888)
			(size 0.3683 0.3683)
			(layers "F.Cu" "F.Mask" "F.Paste")
			(net "GND")
		)
		(pad "C1" smd circle
			(at -3.199892 -4.400042)
			(size 0.3683 0.3683)
			(layers "F.Cu" "F.Mask" "F.Paste")
			(net "P1V538_BMC_NODE1")
		)
		(pad "C2" smd circle
			(at -2.400046 -4.400042)
			(size 0.3683 0.3683)
			(layers "F.Cu" "F.Mask" "F.Paste")
			(net "BMC_NODE1_DDR_D12")
		)
		(pad "C3" smd circle
			(at -1.599946 -4.400042)
			(size 0.3683 0.3683)
			(layers "F.Cu" "F.Mask" "F.Paste")
			(net "BMC_NODE1_DDR_D11")
		)
		(pad "C7" smd circle
			(at 1.599946 -4.400042)
			(size 0.3683 0.3683)
			(layers "F.Cu" "F.Mask" "F.Paste")
			(net "BMC_NODE1_DDR_DQS1_DP")
		)
		(pad "C8" smd circle
			(at 2.400046 -4.400042)
			(size 0.3683 0.3683)
			(layers "F.Cu" "F.Mask" "F.Paste")
			(net "BMC_NODE1_DDR_D13")
		)
		(pad "C9" smd circle
			(at 3.199892 -4.400042)
			(size 0.3683 0.3683)
			(layers "F.Cu" "F.Mask" "F.Paste")
			(net "P1V538_BMC_NODE1")
		)
		(pad "D1" smd circle
			(at -3.199892 -3.599942)
			(size 0.3683 0.3683)
			(layers "F.Cu" "F.Mask" "F.Paste")
			(net "GND")
		)
		(pad "D2" smd circle
			(at -2.400046 -3.599942)
			(size 0.3683 0.3683)
			(layers "F.Cu" "F.Mask" "F.Paste")
			(net "P1V538_BMC_NODE1")
		)
		(pad "D3" smd circle
			(at -1.599946 -3.599942)
			(size 0.3683 0.3683)
			(layers "F.Cu" "F.Mask" "F.Paste")
			(net "BMC_NODE1_DDR_DM1")
		)
		(pad "D7" smd circle
			(at 1.599946 -3.599942)
			(size 0.3683 0.3683)
			(layers "F.Cu" "F.Mask" "F.Paste")
			(net "BMC_NODE1_DDR_D8")
		)
		(pad "D8" smd circle
			(at 2.400046 -3.599942)
			(size 0.3683 0.3683)
			(layers "F.Cu" "F.Mask" "F.Paste")
			(net "GND")
		)
		(pad "D9" smd circle
			(at 3.199892 -3.599942)
			(size 0.3683 0.3683)
			(layers "F.Cu" "F.Mask" "F.Paste")
			(net "P1V538_BMC_NODE1")
		)
		(pad "E1" smd circle
			(at -3.199892 -2.800096)
			(size 0.3683 0.3683)
			(layers "F.Cu" "F.Mask" "F.Paste")
			(net "GND")
		)
		(pad "E2" smd circle
			(at -2.400046 -2.800096)
			(size 0.3683 0.3683)
			(layers "F.Cu" "F.Mask" "F.Paste")
			(net "GND")
		)
		(pad "E3" smd circle
			(at -1.599946 -2.800096)
			(size 0.3683 0.3683)
			(layers "F.Cu" "F.Mask" "F.Paste")
			(net "BMC_NODE1_DDR_D7")
		)
		(pad "E7" smd circle
			(at 1.599946 -2.800096)
			(size 0.3683 0.3683)
			(layers "F.Cu" "F.Mask" "F.Paste")
			(net "BMC_NODE1_DDR_DM0")
		)
		(pad "E8" smd circle
			(at 2.400046 -2.800096)
			(size 0.3683 0.3683)
			(layers "F.Cu" "F.Mask" "F.Paste")
			(net "GND")
		)
		(pad "E9" smd circle
			(at 3.199892 -2.800096)
			(size 0.3683 0.3683)
			(layers "F.Cu" "F.Mask" "F.Paste")
			(net "P1V538_BMC_NODE1")
		)
		(pad "F1" smd circle
			(at -3.199892 -1.999996)
			(size 0.3683 0.3683)
			(layers "F.Cu" "F.Mask" "F.Paste")
			(net "P1V538_BMC_NODE1")
		)
		(pad "F2" smd circle
			(at -2.400046 -1.999996)
			(size 0.3683 0.3683)
			(layers "F.Cu" "F.Mask" "F.Paste")
			(net "BMC_NODE1_DDR_D4")
		)
		(pad "F3" smd circle
			(at -1.599946 -1.999996)
			(size 0.3683 0.3683)
			(layers "F.Cu" "F.Mask" "F.Paste")
			(net "BMC_NODE1_DDR_DQS0_DP")
		)
		(pad "F7" smd circle
			(at 1.599946 -1.999996)
			(size 0.3683 0.3683)
			(layers "F.Cu" "F.Mask" "F.Paste")
			(net "BMC_NODE1_DDR_D3")
		)
		(pad "F8" smd circle
			(at 2.400046 -1.999996)
			(size 0.3683 0.3683)
			(layers "F.Cu" "F.Mask" "F.Paste")
			(net "BMC_NODE1_DDR_D2")
		)
		(pad "F9" smd circle
			(at 3.199892 -1.999996)
			(size 0.3683 0.3683)
			(layers "F.Cu" "F.Mask" "F.Paste")
			(net "GND")
		)
		(pad "G1" smd circle
			(at -3.199892 -1.199896)
			(size 0.3683 0.3683)
			(layers "F.Cu" "F.Mask" "F.Paste")
			(net "GND")
		)
		(pad "G2" smd circle
			(at -2.400046 -1.199896)
			(size 0.3683 0.3683)
			(layers "F.Cu" "F.Mask" "F.Paste")
			(net "BMC_NODE1_DDR_D5")
		)
		(pad "G3" smd circle
			(at -1.599946 -1.199896)
			(size 0.3683 0.3683)
			(layers "F.Cu" "F.Mask" "F.Paste")
			(net "BMC_NODE1_DDR_DQS0_DN")
		)
		(pad "G7" smd circle
			(at 1.599946 -1.199896)
			(size 0.3683 0.3683)
			(layers "F.Cu" "F.Mask" "F.Paste")
			(net "P1V538_BMC_NODE1")
		)
		(pad "G8" smd circle
			(at 2.400046 -1.199896)
			(size 0.3683 0.3683)
			(layers "F.Cu" "F.Mask" "F.Paste")
			(net "GND")
		)
		(pad "G9" smd circle
			(at 3.199892 -1.199896)
			(size 0.3683 0.3683)
			(layers "F.Cu" "F.Mask" "F.Paste")
			(net "GND")
		)
		(pad "H1" smd circle
			(at -3.199892 -0.40005)
			(size 0.3683 0.3683)
			(layers "F.Cu" "F.Mask" "F.Paste")
			(net "P0V75_BMC_VTTREF_NODE1")
		)
		(pad "H2" smd circle
			(at -2.400046 -0.40005)
			(size 0.3683 0.3683)
			(layers "F.Cu" "F.Mask" "F.Paste")
			(net "P1V538_BMC_NODE1")
		)
		(pad "H3" smd circle
			(at -1.599946 -0.40005)
			(size 0.3683 0.3683)
			(layers "F.Cu" "F.Mask" "F.Paste")
			(net "BMC_NODE1_DDR_D1")
		)
		(pad "H7" smd circle
			(at 1.599946 -0.40005)
			(size 0.3683 0.3683)
			(layers "F.Cu" "F.Mask" "F.Paste")
			(net "BMC_NODE1_DDR_D0")
		)
		(pad "H8" smd circle
			(at 2.400046 -0.40005)
			(size 0.3683 0.3683)
			(layers "F.Cu" "F.Mask" "F.Paste")
			(net "BMC_NODE1_DDR_D6")
		)
		(pad "H9" smd circle
			(at 3.199892 -0.40005)
			(size 0.3683 0.3683)
			(layers "F.Cu" "F.Mask" "F.Paste")
			(net "P1V538_BMC_NODE1")
		)
		(pad "J1" smd circle
			(at -3.199892 0.40005)
			(size 0.3683 0.3683)
			(layers "F.Cu" "F.Mask" "F.Paste")
			(net "TP_BMC_NODE1_DDR3_ODT_1NC")
		)
		(pad "J2" smd circle
			(at -2.400046 0.40005)
			(size 0.3683 0.3683)
			(layers "F.Cu" "F.Mask" "F.Paste")
			(net "GND")
		)
		(pad "J3" smd circle
			(at -1.599946 0.40005)
			(size 0.3683 0.3683)
			(layers "F.Cu" "F.Mask" "F.Paste")
			(net "BMC_NODE1_DDR_RAS_L")
		)
		(pad "J7" smd circle
			(at 1.599946 0.40005)
			(size 0.3683 0.3683)
			(layers "F.Cu" "F.Mask" "F.Paste")
			(net "BMC_NODE1_DDR_CLK_DP")
		)
		(pad "J8" smd circle
			(at 2.400046 0.40005)
			(size 0.3683 0.3683)
			(layers "F.Cu" "F.Mask" "F.Paste")
			(net "GND")
		)
		(pad "J9" smd circle
			(at 3.199892 0.40005)
			(size 0.3683 0.3683)
			(layers "F.Cu" "F.Mask" "F.Paste")
			(net "TP_BMC_NODE1_DDR3_CE1_NC1")
		)
		(pad "K1" smd circle
			(at -3.199892 1.199896)
			(size 0.3683 0.3683)
			(layers "F.Cu" "F.Mask" "F.Paste")
			(net "BMC_NODE1_DDR_ODT")
		)
		(pad "K2" smd circle
			(at -2.400046 1.199896)
			(size 0.3683 0.3683)
			(layers "F.Cu" "F.Mask" "F.Paste")
			(net "P1V538_BMC_NODE1")
		)
		(pad "K3" smd circle
			(at -1.599946 1.199896)
			(size 0.3683 0.3683)
			(layers "F.Cu" "F.Mask" "F.Paste")
			(net "BMC_NODE1_DDR_CAS_L")
		)
		(pad "K7" smd circle
			(at 1.599946 1.199896)
			(size 0.3683 0.3683)
			(layers "F.Cu" "F.Mask" "F.Paste")
			(net "BMC_NODE1_DDR_CLK_DN")
		)
		(pad "K8" smd circle
			(at 2.400046 1.199896)
			(size 0.3683 0.3683)
			(layers "F.Cu" "F.Mask" "F.Paste")
			(net "P1V538_BMC_NODE1")
		)
		(pad "K9" smd circle
			(at 3.199892 1.199896)
			(size 0.3683 0.3683)
			(layers "F.Cu" "F.Mask" "F.Paste")
			(net "BMC_NODE1_DDR_CKE")
		)
		(pad "L1" smd circle
			(at -3.199892 1.999996)
			(size 0.3683 0.3683)
			(layers "F.Cu" "F.Mask" "F.Paste")
			(net "TP_BMC_NODE1_DDR3_CS1_L")
		)
		(pad "L2" smd circle
			(at -2.400046 1.999996)
			(size 0.3683 0.3683)
			(layers "F.Cu" "F.Mask" "F.Paste")
			(net "BMC_NODE1_DDR_CS_L")
		)
		(pad "L3" smd circle
			(at -1.599946 1.999996)
			(size 0.3683 0.3683)
			(layers "F.Cu" "F.Mask" "F.Paste")
			(net "BMC_NODE1_DDR_WE_L")
		)
		(pad "L7" smd circle
			(at 1.599946 1.999996)
			(size 0.3683 0.3683)
			(layers "F.Cu" "F.Mask" "F.Paste")
			(net "BMC_NODE1_DDR_MA10")
		)
		(pad "L8" smd circle
			(at 2.400046 1.999996)
			(size 0.3683 0.3683)
			(layers "F.Cu" "F.Mask" "F.Paste")
			(net "BMC_NODE1_DDR3_ZQ")
		)
		(pad "L9" smd circle
			(at 3.199892 1.999996)
			(size 0.3683 0.3683)
			(layers "F.Cu" "F.Mask" "F.Paste")
			(net "TP_BMC_NODE1_DDR3_ZQ1")
		)
		(pad "M1" smd circle
			(at -3.199892 2.800096)
			(size 0.3683 0.3683)
			(layers "F.Cu" "F.Mask" "F.Paste")
			(net "GND")
		)
		(pad "M2" smd circle
			(at -2.400046 2.800096)
			(size 0.3683 0.3683)
			(layers "F.Cu" "F.Mask" "F.Paste")
			(net "BMC_NODE1_DDR_BA0")
		)
		(pad "M3" smd circle
			(at -1.599946 2.800096)
			(size 0.3683 0.3683)
			(layers "F.Cu" "F.Mask" "F.Paste")
			(net "BMC_NODE1_DDR_BA2")
		)
		(pad "M7" smd circle
			(at 1.599946 2.800096)
			(size 0.3683 0.3683)
			(layers "F.Cu" "F.Mask" "F.Paste")
			(net "TP_BMC_NODE1_DDR3_MA15")
		)
		(pad "M8" smd circle
			(at 2.400046 2.800096)
			(size 0.3683 0.3683)
			(layers "F.Cu" "F.Mask" "F.Paste")
			(net "P0V75_BMC_VTTREF_NODE1")
		)
		(pad "M9" smd circle
			(at 3.199892 2.800096)
			(size 0.3683 0.3683)
			(layers "F.Cu" "F.Mask" "F.Paste")
			(net "GND")
		)
		(pad "N1" smd circle
			(at -3.199892 3.599942)
			(size 0.3683 0.3683)
			(layers "F.Cu" "F.Mask" "F.Paste")
			(net "P1V538_BMC_NODE1")
		)
		(pad "N2" smd circle
			(at -2.400046 3.599942)
			(size 0.3683 0.3683)
			(layers "F.Cu" "F.Mask" "F.Paste")
			(net "BMC_NODE1_DDR_MA3")
		)
		(pad "N3" smd circle
			(at -1.599946 3.599942)
			(size 0.3683 0.3683)
			(layers "F.Cu" "F.Mask" "F.Paste")
			(net "BMC_NODE1_DDR_MA0")
		)
		(pad "N7" smd circle
			(at 1.599946 3.599942)
			(size 0.3683 0.3683)
			(layers "F.Cu" "F.Mask" "F.Paste")
			(net "BMC_NODE1_DDR_MA12")
		)
		(pad "N8" smd circle
			(at 2.400046 3.599942)
			(size 0.3683 0.3683)
			(layers "F.Cu" "F.Mask" "F.Paste")
			(net "BMC_NODE1_DDR_BA1")
		)
		(pad "N9" smd circle
			(at 3.199892 3.599942)
			(size 0.3683 0.3683)
			(layers "F.Cu" "F.Mask" "F.Paste")
			(net "P1V538_BMC_NODE1")
		)
		(pad "P1" smd circle
			(at -3.199892 4.400042)
			(size 0.3683 0.3683)
			(layers "F.Cu" "F.Mask" "F.Paste")
			(net "GND")
		)
		(pad "P2" smd circle
			(at -2.400046 4.400042)
			(size 0.3683 0.3683)
			(layers "F.Cu" "F.Mask" "F.Paste")
			(net "BMC_NODE1_DDR_MA5")
		)
		(pad "P3" smd circle
			(at -1.599946 4.400042)
			(size 0.3683 0.3683)
			(layers "F.Cu" "F.Mask" "F.Paste")
			(net "BMC_NODE1_DDR_MA2")
		)
		(pad "P7" smd circle
			(at 1.599946 4.400042)
			(size 0.3683 0.3683)
			(layers "F.Cu" "F.Mask" "F.Paste")
			(net "BMC_NODE1_DDR_MA1")
		)
		(pad "P8" smd circle
			(at 2.400046 4.400042)
			(size 0.3683 0.3683)
			(layers "F.Cu" "F.Mask" "F.Paste")
			(net "BMC_NODE1_DDR_MA4")
		)
		(pad "P9" smd circle
			(at 3.199892 4.400042)
			(size 0.3683 0.3683)
			(layers "F.Cu" "F.Mask" "F.Paste")
			(net "GND")
		)
		(pad "R1" smd circle
			(at -3.199892 5.199888)
			(size 0.3683 0.3683)
			(layers "F.Cu" "F.Mask" "F.Paste")
			(net "P1V538_BMC_NODE1")
		)
		(pad "R2" smd circle
			(at -2.400046 5.199888)
			(size 0.3683 0.3683)
			(layers "F.Cu" "F.Mask" "F.Paste")
			(net "BMC_NODE1_DDR_MA7")
		)
		(pad "R3" smd circle
			(at -1.599946 5.199888)
			(size 0.3683 0.3683)
			(layers "F.Cu" "F.Mask" "F.Paste")
			(net "BMC_NODE1_DDR_MA9")
		)
		(pad "R7" smd circle
			(at 1.599946 5.199888)
			(size 0.3683 0.3683)
			(layers "F.Cu" "F.Mask" "F.Paste")
			(net "BMC_NODE1_DDR_MA11")
		)
		(pad "R8" smd circle
			(at 2.400046 5.199888)
			(size 0.3683 0.3683)
			(layers "F.Cu" "F.Mask" "F.Paste")
			(net "BMC_NODE1_DDR_MA6")
		)
		(pad "R9" smd circle
			(at 3.199892 5.199888)
			(size 0.3683 0.3683)
			(layers "F.Cu" "F.Mask" "F.Paste")
			(net "P1V538_BMC_NODE1")
		)
		(pad "T1" smd circle
			(at -3.199892 5.999988)
			(size 0.3683 0.3683)
			(layers "F.Cu" "F.Mask" "F.Paste")
			(net "GND")
		)
		(pad "T2" smd circle
			(at -2.400046 5.999988)
			(size 0.3683 0.3683)
			(layers "F.Cu" "F.Mask" "F.Paste")
			(net "BMC_NODE1_DDR_RST_L")
		)
		(pad "T3" smd circle
			(at -1.599946 5.999988)
			(size 0.3683 0.3683)
			(layers "F.Cu" "F.Mask" "F.Paste")
			(net "BMC_NODE1_DDR_MA13")
		)
		(pad "T7" smd circle
			(at 1.599946 5.999988)
			(size 0.3683 0.3683)
			(layers "F.Cu" "F.Mask" "F.Paste")
			(net "BMC_NODE1_DDR_MA14")
		)
		(pad "T8" smd circle
			(at 2.400046 5.999988)
			(size 0.3683 0.3683)
			(layers "F.Cu" "F.Mask" "F.Paste")
			(net "BMC_NODE1_DDR_MA8")
		)
		(pad "T9" smd circle
			(at 3.199892 5.999988)
			(size 0.3683 0.3683)
			(layers "F.Cu" "F.Mask" "F.Paste")
			(net "GND")
		)
	)
)
